(kicad_pcb
	(version 20260206)
	(generator "pcbnew")
	(generator_version "10.0")
	(general
		(thickness 1.6)
		(legacy_teardrops no)
	)
	(paper "A4")
	(title_block
		(title "04192023_DAF0TMB3IC0_F0TG_MB_C_brd_V02_OCP.brd")
		(comment 1 "Grand Teton / footprints 953-959 of 8354")
	)
	(layers
		(0 "F.Cu" signal "TOP")
		(4 "In1.Cu" signal "GND")
		(6 "In2.Cu" signal "IN1")
		(8 "In3.Cu" signal "GND1")
		(10 "In4.Cu" signal "IN2")
		(12 "In5.Cu" signal "GND2")
		(14 "In6.Cu" signal "IN3")
		(16 "In7.Cu" signal "GND3")
		(18 "In8.Cu" signal "VCC")
		(20 "In9.Cu" signal "VCC1")
		(22 "In10.Cu" signal "GND4")
		(24 "In11.Cu" signal "IN4")
		(26 "In12.Cu" signal "GND5")
		(28 "In13.Cu" signal "IN5")
		(30 "In14.Cu" signal "GND6")
		(32 "In15.Cu" signal "IN6")
		(34 "In16.Cu" signal "GND7")
		(2 "B.Cu" signal "BOTTOM")
		(9 "F.Adhes" user "F.Adhesive")
		(11 "B.Adhes" user "B.Adhesive")
		(13 "F.Paste" user "Package Geometry/Pastemask Top")
		(15 "B.Paste" user "Package Geometry/Pastemask Bottom")
		(5 "F.SilkS" user "Ref Des/Silkscreen Top")
		(7 "B.SilkS" user "Ref Des/Silkscreen Bottom")
		(1 "F.Mask" user "Board Geometry/Soldermask Top")
		(3 "B.Mask" user "Board Geometry/Soldermask Bottom")
		(17 "Dwgs.User" user "User.Drawings")
		(19 "Cmts.User" user "User.Comments")
		(21 "Eco1.User" user "User.Eco1")
		(23 "Eco2.User" user "User.Eco2")
		(25 "Edge.Cuts" user "Board Geometry/Outline")
		(27 "Margin" user)
		(31 "F.CrtYd" user "Package Geometry/Place Bound Top")
		(29 "B.CrtYd" user "Package Geometry/Place Bound Bottom")
		(35 "F.Fab" user "Ref Des/Assembly Top")
		(33 "B.Fab" user "Ref Des/Assembly Bottom")
	)
	(footprint ""
		(layer "F.Cu")
		(at 318.300608 -25.27935 90)
		(property "Reference" "C553"
			(at 0 0 90)
			(layer "F.SilkS")
			(hide yes)
			(effects
				(font
					(size 1.27 1.27)
				)
			)
		)
		(property "Value" ""
			(at 0 0 90)
			(layer "F.Fab")
			(effects
				(font
					(size 1.27 1.27)
				)
			)
		)
		(duplicate_pad_numbers_are_jumpers no)
		(fp_line
			(start 0.7874 -0.4064)
			(end 0.7874 0.4064)
			(stroke
				(width 0.1524)
				(type default)
			)
			(layer "F.SilkS")
		)
		(fp_line
			(start -0.7874 -0.4064)
			(end 0.7874 -0.4064)
			(stroke
				(width 0.1524)
				(type default)
			)
			(layer "F.SilkS")
		)
		(fp_line
			(start 0.7874 0.4064)
			(end -0.7874 0.4064)
			(stroke
				(width 0.1524)
				(type default)
			)
			(layer "F.SilkS")
		)
		(fp_line
			(start -0.7874 0.4064)
			(end -0.7874 -0.4064)
			(stroke
				(width 0.1524)
				(type default)
			)
			(layer "F.SilkS")
		)
		(fp_line
			(start -0.12065 -0.305054)
			(end -0.12065 -0.2794)
			(stroke
				(width 0.1)
				(type default)
			)
			(layer "F.Fab")
		)
		(fp_line
			(start -0.67945 -0.305054)
			(end -0.12065 -0.305054)
			(stroke
				(width 0.1)
				(type default)
			)
			(layer "F.Fab")
		)
		(fp_line
			(start 0.67945 -0.3048)
			(end 0.67945 0.3048)
			(stroke
				(width 0.1)
				(type default)
			)
			(layer "F.Fab")
		)
		(fp_line
			(start 0.12065 -0.3048)
			(end 0.67945 -0.3048)
			(stroke
				(width 0.1)
				(type default)
			)
			(layer "F.Fab")
		)
		(fp_line
			(start 0.12065 -0.2794)
			(end 0.12065 -0.3048)
			(stroke
				(width 0.1)
				(type default)
			)
			(layer "F.Fab")
		)
		(fp_line
			(start -0.12065 -0.2794)
			(end 0.12065 -0.2794)
			(stroke
				(width 0.1)
				(type default)
			)
			(layer "F.Fab")
		)
		(fp_line
			(start 0.120396 0.2794)
			(end -0.12065 0.2794)
			(stroke
				(width 0.1)
				(type default)
			)
			(layer "F.Fab")
		)
		(fp_line
			(start -0.12065 0.2794)
			(end -0.12065 0.3048)
			(stroke
				(width 0.1)
				(type default)
			)
			(layer "F.Fab")
		)
		(fp_line
			(start 0.67945 0.3048)
			(end 0.120396 0.3048)
			(stroke
				(width 0.1)
				(type default)
			)
			(layer "F.Fab")
		)
		(fp_line
			(start 0.120396 0.3048)
			(end 0.120396 0.2794)
			(stroke
				(width 0.1)
				(type default)
			)
			(layer "F.Fab")
		)
		(fp_line
			(start -0.12065 0.3048)
			(end -0.67945 0.3048)
			(stroke
				(width 0.1)
				(type default)
			)
			(layer "F.Fab")
		)
		(fp_line
			(start -0.67945 0.3048)
			(end -0.67945 -0.305054)
			(stroke
				(width 0.1)
				(type default)
			)
			(layer "F.Fab")
		)
		(pad "1" smd circle
			(at -0.40005 0 90)
			(size 0 0)
			(layers "F.Cu" "F.Mask" "F.Paste")
			(net "P3V3_AUX")
		)
		(pad "2" smd circle
			(at 0.40005 0 90)
			(size 0 0)
			(layers "F.Cu" "F.Mask" "F.Paste")
			(net "GND")
		)
	)
	(footprint ""
		(layer "F.Cu")
		(at 74.34707 -148.451316 -90)
		(property "Reference" "C675"
			(at 0 0 270)
			(layer "F.SilkS")
			(hide yes)
			(effects
				(font
					(size 1.27 1.27)
				)
			)
		)
		(property "Value" ""
			(at 0 0 270)
			(layer "F.Fab")
			(effects
				(font
					(size 1.27 1.27)
				)
			)
		)
		(duplicate_pad_numbers_are_jumpers no)
		(fp_line
			(start -0.7874 0.4064)
			(end -0.7874 -0.4064)
			(stroke
				(width 0.1524)
				(type default)
			)
			(layer "F.SilkS")
		)
		(fp_line
			(start 0.7874 0.4064)
			(end -0.7874 0.4064)
			(stroke
				(width 0.1524)
				(type default)
			)
			(layer "F.SilkS")
		)
		(fp_line
			(start -0.7874 -0.4064)
			(end 0.7874 -0.4064)
			(stroke
				(width 0.1524)
				(type default)
			)
			(layer "F.SilkS")
		)
		(fp_line
			(start 0.7874 -0.4064)
			(end 0.7874 0.4064)
			(stroke
				(width 0.1524)
				(type default)
			)
			(layer "F.SilkS")
		)
		(fp_line
			(start -0.67945 0.3048)
			(end -0.67945 -0.305054)
			(stroke
				(width 0.1)
				(type default)
			)
			(layer "F.Fab")
		)
		(fp_line
			(start -0.12065 0.3048)
			(end -0.67945 0.3048)
			(stroke
				(width 0.1)
				(type default)
			)
			(layer "F.Fab")
		)
		(fp_line
			(start 0.120396 0.3048)
			(end 0.120396 0.2794)
			(stroke
				(width 0.1)
				(type default)
			)
			(layer "F.Fab")
		)
		(fp_line
			(start 0.67945 0.3048)
			(end 0.120396 0.3048)
			(stroke
				(width 0.1)
				(type default)
			)
			(layer "F.Fab")
		)
		(fp_line
			(start -0.12065 0.2794)
			(end -0.12065 0.3048)
			(stroke
				(width 0.1)
				(type default)
			)
			(layer "F.Fab")
		)
		(fp_line
			(start 0.120396 0.2794)
			(end -0.12065 0.2794)
			(stroke
				(width 0.1)
				(type default)
			)
			(layer "F.Fab")
		)
		(fp_line
			(start -0.12065 -0.2794)
			(end 0.12065 -0.2794)
			(stroke
				(width 0.1)
				(type default)
			)
			(layer "F.Fab")
		)
		(fp_line
			(start 0.12065 -0.2794)
			(end 0.12065 -0.3048)
			(stroke
				(width 0.1)
				(type default)
			)
			(layer "F.Fab")
		)
		(fp_line
			(start 0.12065 -0.3048)
			(end 0.67945 -0.3048)
			(stroke
				(width 0.1)
				(type default)
			)
			(layer "F.Fab")
		)
		(fp_line
			(start 0.67945 -0.3048)
			(end 0.67945 0.3048)
			(stroke
				(width 0.1)
				(type default)
			)
			(layer "F.Fab")
		)
		(fp_line
			(start -0.67945 -0.305054)
			(end -0.12065 -0.305054)
			(stroke
				(width 0.1)
				(type default)
			)
			(layer "F.Fab")
		)
		(fp_line
			(start -0.12065 -0.305054)
			(end -0.12065 -0.2794)
			(stroke
				(width 0.1)
				(type default)
			)
			(layer "F.Fab")
		)
		(pad "1" smd circle
			(at -0.40005 0 270)
			(size 0 0)
			(layers "F.Cu" "F.Mask" "F.Paste")
			(net "PVDD18_S5_P1_EN")
		)
		(pad "2" smd circle
			(at 0.40005 0 270)
			(size 0 0)
			(layers "F.Cu" "F.Mask" "F.Paste")
			(net "GND")
		)
	)
	(footprint ""
		(layer "F.Cu")
		(at 111.506 -413.385)
		(property "Reference" "R586"
			(at 0 0 0)
			(layer "F.SilkS")
			(hide yes)
			(effects
				(font
					(size 1.27 1.27)
				)
			)
		)
		(property "Value" ""
			(at 0 0 0)
			(layer "F.Fab")
			(effects
				(font
					(size 1.27 1.27)
				)
			)
		)
		(duplicate_pad_numbers_are_jumpers no)
		(fp_line
			(start -1.2954 -0.5842)
			(end 1.2954 -0.5842)
			(stroke
				(width 0.1524)
				(type default)
			)
			(layer "F.SilkS")
		)
		(fp_line
			(start -1.2954 0.5842)
			(end -1.2954 -0.5842)
			(stroke
				(width 0.1524)
				(type default)
			)
			(layer "F.SilkS")
		)
		(fp_line
			(start 1.2954 -0.5842)
			(end 1.2954 0.5842)
			(stroke
				(width 0.1524)
				(type default)
			)
			(layer "F.SilkS")
		)
		(fp_line
			(start 1.2954 0.5842)
			(end -1.2954 0.5842)
			(stroke
				(width 0.1524)
				(type default)
			)
			(layer "F.SilkS")
		)
		(fp_line
			(start -1.1938 -0.406654)
			(end -0.8636 -0.406654)
			(stroke
				(width 0.1)
				(type default)
			)
			(layer "F.Fab")
		)
		(fp_line
			(start -1.1938 0.4064)
			(end -1.1938 -0.406654)
			(stroke
				(width 0.1)
				(type default)
			)
			(layer "F.Fab")
		)
		(fp_line
			(start -0.8636 -0.4572)
			(end 0.8636 -0.4572)
			(stroke
				(width 0.1)
				(type default)
			)
			(layer "F.Fab")
		)
		(fp_line
			(start -0.8636 -0.406654)
			(end -0.8636 -0.4572)
			(stroke
				(width 0.1)
				(type default)
			)
			(layer "F.Fab")
		)
		(fp_line
			(start -0.8636 0.4064)
			(end -1.1938 0.4064)
			(stroke
				(width 0.1)
				(type default)
			)
			(layer "F.Fab")
		)
		(fp_line
			(start -0.8636 0.4318)
			(end -0.8636 0.4064)
			(stroke
				(width 0.1)
				(type default)
			)
			(layer "F.Fab")
		)
		(fp_line
			(start -0.8636 0.4572)
			(end -0.8636 0.4318)
			(stroke
				(width 0.1)
				(type default)
			)
			(layer "F.Fab")
		)
		(fp_line
			(start 0.8636 -0.4572)
			(end 0.8636 -0.406654)
			(stroke
				(width 0.1)
				(type default)
			)
			(layer "F.Fab")
		)
		(fp_line
			(start 0.8636 -0.406654)
			(end 1.1938 -0.406654)
			(stroke
				(width 0.1)
				(type default)
			)
			(layer "F.Fab")
		)
		(fp_line
			(start 0.8636 0.4064)
			(end 0.8636 0.4572)
			(stroke
				(width 0.1)
				(type default)
			)
			(layer "F.Fab")
		)
		(fp_line
			(start 0.8636 0.4572)
			(end -0.8636 0.4572)
			(stroke
				(width 0.1)
				(type default)
			)
			(layer "F.Fab")
		)
		(fp_line
			(start 1.1938 -0.406654)
			(end 1.1938 0.4064)
			(stroke
				(width 0.1)
				(type default)
			)
			(layer "F.Fab")
		)
		(fp_line
			(start 1.1938 0.4064)
			(end 0.8636 0.4064)
			(stroke
				(width 0.1)
				(type default)
			)
			(layer "F.Fab")
		)
		(pad "1" smd rect
			(at -0.7366 0 270)
			(size 0.7112 0.8128)
			(layers "F.Cu" "F.Mask" "F.Paste")
			(net "P3V3_9ZXL045_P1")
		)
		(pad "2" smd rect
			(at 0.7366 0 270)
			(size 0.7112 0.8128)
			(layers "F.Cu" "F.Mask" "F.Paste")
			(net "P3V3_9ZXL045_P1_VDDA")
		)
	)
	(footprint ""
		(layer "F.Cu")
		(at 319.242186 -361.061 90)
		(property "Reference" "PR53"
			(at 0 0 90)
			(layer "F.SilkS")
			(hide yes)
			(effects
				(font
					(size 1.27 1.27)
				)
			)
		)
		(property "Value" ""
			(at 0 0 90)
			(layer "F.Fab")
			(effects
				(font
					(size 1.27 1.27)
				)
			)
		)
		(duplicate_pad_numbers_are_jumpers no)
		(fp_line
			(start 0.7874 -0.4064)
			(end 0.7874 0.4064)
			(stroke
				(width 0.1524)
				(type default)
			)
			(layer "F.SilkS")
		)
		(fp_line
			(start -0.7874 -0.4064)
			(end 0.7874 -0.4064)
			(stroke
				(width 0.1524)
				(type default)
			)
			(layer "F.SilkS")
		)
		(fp_line
			(start 0.7874 0.4064)
			(end -0.7874 0.4064)
			(stroke
				(width 0.1524)
				(type default)
			)
			(layer "F.SilkS")
		)
		(fp_line
			(start -0.7874 0.4064)
			(end -0.7874 -0.4064)
			(stroke
				(width 0.1524)
				(type default)
			)
			(layer "F.SilkS")
		)
		(fp_line
			(start -0.12065 -0.305054)
			(end -0.12065 -0.2794)
			(stroke
				(width 0.1)
				(type default)
			)
			(layer "F.Fab")
		)
		(fp_line
			(start -0.67945 -0.305054)
			(end -0.12065 -0.305054)
			(stroke
				(width 0.1)
				(type default)
			)
			(layer "F.Fab")
		)
		(fp_line
			(start 0.67945 -0.3048)
			(end 0.67945 0.3048)
			(stroke
				(width 0.1)
				(type default)
			)
			(layer "F.Fab")
		)
		(fp_line
			(start 0.12065 -0.3048)
			(end 0.67945 -0.3048)
			(stroke
				(width 0.1)
				(type default)
			)
			(layer "F.Fab")
		)
		(fp_line
			(start 0.12065 -0.2794)
			(end 0.12065 -0.3048)
			(stroke
				(width 0.1)
				(type default)
			)
			(layer "F.Fab")
		)
		(fp_line
			(start -0.12065 -0.2794)
			(end 0.12065 -0.2794)
			(stroke
				(width 0.1)
				(type default)
			)
			(layer "F.Fab")
		)
		(fp_line
			(start 0.120396 0.2794)
			(end -0.12065 0.2794)
			(stroke
				(width 0.1)
				(type default)
			)
			(layer "F.Fab")
		)
		(fp_line
			(start -0.12065 0.2794)
			(end -0.12065 0.3048)
			(stroke
				(width 0.1)
				(type default)
			)
			(layer "F.Fab")
		)
		(fp_line
			(start 0.67945 0.3048)
			(end 0.120396 0.3048)
			(stroke
				(width 0.1)
				(type default)
			)
			(layer "F.Fab")
		)
		(fp_line
			(start 0.120396 0.3048)
			(end 0.120396 0.2794)
			(stroke
				(width 0.1)
				(type default)
			)
			(layer "F.Fab")
		)
		(fp_line
			(start -0.12065 0.3048)
			(end -0.67945 0.3048)
			(stroke
				(width 0.1)
				(type default)
			)
			(layer "F.Fab")
		)
		(fp_line
			(start -0.67945 0.3048)
			(end -0.67945 -0.305054)
			(stroke
				(width 0.1)
				(type default)
			)
			(layer "F.Fab")
		)
		(pad "1" smd circle
			(at -0.40005 0 90)
			(size 0 0)
			(layers "F.Cu" "F.Mask" "F.Paste")
			(net "P5V_AUX")
		)
		(pad "2" smd circle
			(at 0.40005 0 90)
			(size 0 0)
			(layers "F.Cu" "F.Mask" "F.Paste")
			(net "PVDDCR_CPU1_P0_VMON")
		)
	)
	(footprint ""
		(layer "F.Cu")
		(at 453.719946 -106.408728)
		(property "Reference" "R1907"
			(at 0 0 0)
			(layer "F.SilkS")
			(hide yes)
			(effects
				(font
					(size 1.27 1.27)
				)
			)
		)
		(property "Value" ""
			(at 0 0 0)
			(layer "F.Fab")
			(effects
				(font
					(size 1.27 1.27)
				)
			)
		)
		(duplicate_pad_numbers_are_jumpers no)
		(fp_line
			(start -0.7874 -0.4064)
			(end 0.7874 -0.4064)
			(stroke
				(width 0.1524)
				(type default)
			)
			(layer "F.SilkS")
		)
		(fp_line
			(start -0.7874 0.4064)
			(end -0.7874 -0.4064)
			(stroke
				(width 0.1524)
				(type default)
			)
			(layer "F.SilkS")
		)
		(fp_line
			(start 0.7874 -0.4064)
			(end 0.7874 0.4064)
			(stroke
				(width 0.1524)
				(type default)
			)
			(layer "F.SilkS")
		)
		(fp_line
			(start 0.7874 0.4064)
			(end -0.7874 0.4064)
			(stroke
				(width 0.1524)
				(type default)
			)
			(layer "F.SilkS")
		)
		(fp_line
			(start -0.67945 -0.305054)
			(end -0.12065 -0.305054)
			(stroke
				(width 0.1)
				(type default)
			)
			(layer "F.Fab")
		)
		(fp_line
			(start -0.67945 0.3048)
			(end -0.67945 -0.305054)
			(stroke
				(width 0.1)
				(type default)
			)
			(layer "F.Fab")
		)
		(fp_line
			(start -0.12065 -0.305054)
			(end -0.12065 -0.2794)
			(stroke
				(width 0.1)
				(type default)
			)
			(layer "F.Fab")
		)
		(fp_line
			(start -0.12065 -0.2794)
			(end 0.12065 -0.2794)
			(stroke
				(width 0.1)
				(type default)
			)
			(layer "F.Fab")
		)
		(fp_line
			(start -0.12065 0.2794)
			(end -0.12065 0.3048)
			(stroke
				(width 0.1)
				(type default)
			)
			(layer "F.Fab")
		)
		(fp_line
			(start -0.12065 0.3048)
			(end -0.67945 0.3048)
			(stroke
				(width 0.1)
				(type default)
			)
			(layer "F.Fab")
		)
		(fp_line
			(start 0.120396 0.2794)
			(end -0.12065 0.2794)
			(stroke
				(width 0.1)
				(type default)
			)
			(layer "F.Fab")
		)
		(fp_line
			(start 0.120396 0.3048)
			(end 0.120396 0.2794)
			(stroke
				(width 0.1)
				(type default)
			)
			(layer "F.Fab")
		)
		(fp_line
			(start 0.12065 -0.3048)
			(end 0.67945 -0.3048)
			(stroke
				(width 0.1)
				(type default)
			)
			(layer "F.Fab")
		)
		(fp_line
			(start 0.12065 -0.2794)
			(end 0.12065 -0.3048)
			(stroke
				(width 0.1)
				(type default)
			)
			(layer "F.Fab")
		)
		(fp_line
			(start 0.67945 -0.3048)
			(end 0.67945 0.3048)
			(stroke
				(width 0.1)
				(type default)
			)
			(layer "F.Fab")
		)
		(fp_line
			(start 0.67945 0.3048)
			(end 0.120396 0.3048)
			(stroke
				(width 0.1)
				(type default)
			)
			(layer "F.Fab")
		)
		(pad "1" smd circle
			(at -0.40005 0)
			(size 0 0)
			(layers "F.Cu" "F.Mask" "F.Paste")
			(net "P3V3_AUX")
		)
		(pad "2" smd circle
			(at 0.40005 0)
			(size 0 0)
			(layers "F.Cu" "F.Mask" "F.Paste")
			(net "OCP_SFF_PRSNT1_R_N")
		)
	)
	(footprint ""
		(layer "F.Cu")
		(at 447.052954 -401.785328 -90)
		(property "Reference" "PC6563"
			(at 0 0 270)
			(layer "F.SilkS")
			(hide yes)
			(effects
				(font
					(size 1.27 1.27)
				)
			)
		)
		(property "Value" ""
			(at 0 0 270)
			(layer "F.Fab")
			(effects
				(font
					(size 1.27 1.27)
				)
			)
		)
		(duplicate_pad_numbers_are_jumpers no)
		(fp_line
			(start -0.7874 0.4064)
			(end -0.7874 -0.4064)
			(stroke
				(width 0.1524)
				(type default)
			)
			(layer "F.SilkS")
		)
		(fp_line
			(start 0.7874 0.4064)
			(end -0.7874 0.4064)
			(stroke
				(width 0.1524)
				(type default)
			)
			(layer "F.SilkS")
		)
		(fp_line
			(start -0.7874 -0.4064)
			(end 0.7874 -0.4064)
			(stroke
				(width 0.1524)
				(type default)
			)
			(layer "F.SilkS")
		)
		(fp_line
			(start 0.7874 -0.4064)
			(end 0.7874 0.4064)
			(stroke
				(width 0.1524)
				(type default)
			)
			(layer "F.SilkS")
		)
		(fp_line
			(start -0.67945 0.3048)
			(end -0.67945 -0.305054)
			(stroke
				(width 0.1)
				(type default)
			)
			(layer "F.Fab")
		)
		(fp_line
			(start -0.12065 0.3048)
			(end -0.67945 0.3048)
			(stroke
				(width 0.1)
				(type default)
			)
			(layer "F.Fab")
		)
		(fp_line
			(start 0.120396 0.3048)
			(end 0.120396 0.2794)
			(stroke
				(width 0.1)
				(type default)
			)
			(layer "F.Fab")
		)
		(fp_line
			(start 0.67945 0.3048)
			(end 0.120396 0.3048)
			(stroke
				(width 0.1)
				(type default)
			)
			(layer "F.Fab")
		)
		(fp_line
			(start -0.12065 0.2794)
			(end -0.12065 0.3048)
			(stroke
				(width 0.1)
				(type default)
			)
			(layer "F.Fab")
		)
		(fp_line
			(start 0.120396 0.2794)
			(end -0.12065 0.2794)
			(stroke
				(width 0.1)
				(type default)
			)
			(layer "F.Fab")
		)
		(fp_line
			(start -0.12065 -0.2794)
			(end 0.12065 -0.2794)
			(stroke
				(width 0.1)
				(type default)
			)
			(layer "F.Fab")
		)
		(fp_line
			(start 0.12065 -0.2794)
			(end 0.12065 -0.3048)
			(stroke
				(width 0.1)
				(type default)
			)
			(layer "F.Fab")
		)
		(fp_line
			(start 0.12065 -0.3048)
			(end 0.67945 -0.3048)
			(stroke
				(width 0.1)
				(type default)
			)
			(layer "F.Fab")
		)
		(fp_line
			(start 0.67945 -0.3048)
			(end 0.67945 0.3048)
			(stroke
				(width 0.1)
				(type default)
			)
			(layer "F.Fab")
		)
		(fp_line
			(start -0.67945 -0.305054)
			(end -0.12065 -0.305054)
			(stroke
				(width 0.1)
				(type default)
			)
			(layer "F.Fab")
		)
		(fp_line
			(start -0.12065 -0.305054)
			(end -0.12065 -0.2794)
			(stroke
				(width 0.1)
				(type default)
			)
			(layer "F.Fab")
		)
		(pad "1" smd circle
			(at -0.40005 0 270)
			(size 0 0)
			(layers "F.Cu" "F.Mask" "F.Paste")
			(net "SW_P0V9_RETIMER_CPU0_BOOT1_RC")
		)
		(pad "2" smd circle
			(at 0.40005 0 270)
			(size 0 0)
			(layers "F.Cu" "F.Mask" "F.Paste")
			(net "SW_P0V9_RETIMER_CPU0_PH1")
		)
	)
	(footprint ""
		(layer "F.Cu")
		(at 219.61475 -347.604588 180)
		(property "Reference" ""
			(at 0 0 180)
			(layer "F.SilkS")
			(hide yes)
			(effects
				(font
					(size 1.27 1.27)
				)
			)
		)
		(property "Value" ""
			(at 0 0 180)
			(layer "F.Fab")
			(effects
				(font
					(size 1.27 1.27)
				)
			)
		)
		(duplicate_pad_numbers_are_jumpers no)
		(pad "1" smd circle
			(at 0 0 180)
			(size 0.9906 0.9906)
			(layers "F.Cu" "F.Mask" "F.Paste")
			(net "Net_48")
		)
		(zone
			(layer "F.Cu")
			(hatch none 0.5)
			(connect_pads
				(clearance 0)
			)
			(min_thickness 0.25)
			(keepout
				(tracks not_allowed)
				(vias allowed)
				(pads allowed)
				(copperpour not_allowed)
				(footprints allowed)
			)
			(placement
				(enabled no)
				(sheetname "")
			)
			(fill
				(thermal_gap 0.5)
				(thermal_bridge_width 0.5)
				(island_removal_mode 0)
			)
			(polygon
				(pts
					(arc
						(start 221.24035 -347.604588)
						(mid 217.98915 -347.604588)
						(end 221.24035 -347.604588)
					)
				)
			)
		)
	)
)
